# TIMECARD (Time Appliance Project (Time Card)) — schematic netlist excerpt (pin names and nets, part order shuffled) for the footprints in the layout excerpt that follows; sources: Cadence DE-HDL packaged netlist, KiCad conversion of R4006-B0001-02_R01.brd

R199  RESISTOR  4.7KOHM 1%  pkg SMC_0402R_H016  page 10 : \1\ = UNNAMED_127_MT25QL128ABA1ESESOP ; \2\ = XP3R3V_FPGA
C165  CAPACITOR  0.1UF 10V 10%  pkg SMC_0402R_H022  page 14 : \1\ = XP3R3V_FPGA ; \2\ = SG

(kicad_pcb
	(version 20260206)
	(generator "pcbnew")
	(generator_version "10.0")
	(general
		(thickness 1.6)
		(legacy_teardrops no)
	)
	(paper "A4")
	(title_block
		(title "timecard-production-celestica-r4006 — R4006-B0001-02_R01.brd")
		(comment 1 "Time Appliance Project (Time Card) / footprints 819-820 of 1113")
	)
	(layers
		(0 "F.Cu" signal "TOP")
		(4 "In1.Cu" signal "L02_GND1")
		(6 "In2.Cu" signal "L03_SIG1")
		(8 "In3.Cu" signal "L04_GND2")
		(10 "In4.Cu" signal "L05_VCC1")
		(12 "In5.Cu" signal "L06_VCC2")
		(14 "In6.Cu" signal "L07_GND3")
		(16 "In7.Cu" signal "L08_SIG2")
		(18 "In8.Cu" signal "L09_GND4")
		(2 "B.Cu" signal "BOTTOM")
		(9 "F.Adhes" user "F.Adhesive")
		(11 "B.Adhes" user "B.Adhesive")
		(13 "F.Paste" user "Package Geometry/Pastemask Top")
		(15 "B.Paste" user "Package Geometry/Pastemask Bottom")
		(5 "F.SilkS" user "Ref Des/Silkscreen Top")
		(7 "B.SilkS" user "Ref Des/Silkscreen Bottom")
		(1 "F.Mask" user "Board Geometry/Soldermask Top")
		(3 "B.Mask" user "Board Geometry/Soldermask Bottom")
		(17 "Dwgs.User" user "User.Drawings")
		(19 "Cmts.User" user "User.Comments")
		(21 "Eco1.User" user "User.Eco1")
		(23 "Eco2.User" user "User.Eco2")
		(25 "Edge.Cuts" user "Board Geometry/Outline")
		(27 "Margin" user)
		(31 "F.CrtYd" user "Package Geometry/Place Bound Top")
		(29 "B.CrtYd" user "Package Geometry/Place Bound Bottom")
		(35 "F.Fab" user "Ref Des/Assembly Top")
		(33 "B.Fab" user "Ref Des/Assembly Bottom")
	)
	(footprint ""
		(layer "B.Cu")
		(at 115.166394 -44.577 180)
		(property "Reference" "C165"
			(at 43.030394 -1.93675 0)
			(unlocked yes)
			(layer "B.SilkS")
			(effects
				(font
					(size 0.635 0.4064)
					(thickness 0.1524)
				)
				(justify mirror)
			)
		)
		(property "Value" "VAL*"
			(at -0.0762 2.067306 180)
			(unlocked yes)
			(layer "B.Fab")
			(hide yes)
			(effects
				(font
					(size 0.7874 0.5842)
					(thickness 0.1524)
				)
				(justify mirror)
			)
		)
		(property "Device Type" "CAPACITOR-G105-0B104-CK,0.1UF,A"
			(at -0.0508 1.127506 180)
			(unlocked yes)
			(layer "B.Fab")
			(hide yes)
			(effects
				(font
					(size 0.7874 0.5842)
					(thickness 0.1524)
				)
				(justify mirror)
			)
		)
		(property "User Part Number" "PARTNUM*"
			(at -0.1016 4.023106 180)
			(unlocked yes)
			(layer "Cmts.User")
			(hide yes)
			(effects
				(font
					(size 0.7874 0.5842)
					(thickness 0.1524)
				)
				(justify mirror)
			)
		)
		(property "Tolerance" "TOL*"
			(at -0.0762 3.032506 180)
			(unlocked yes)
			(layer "Cmts.User")
			(hide yes)
			(effects
				(font
					(size 0.7874 0.5842)
					(thickness 0.1524)
				)
				(justify mirror)
			)
		)
		(duplicate_pad_numbers_are_jumpers no)
		(fp_line
			(start 1.143 0.5588)
			(end -1.143 0.5588)
			(stroke
				(width 0.1)
				(type default)
			)
			(layer "B.SilkS")
		)
		(fp_line
			(start 1.143 -0.5588)
			(end 1.143 0.5588)
			(stroke
				(width 0.1)
				(type default)
			)
			(layer "B.SilkS")
		)
		(fp_line
			(start -1.143 0.5588)
			(end -1.143 -0.5588)
			(stroke
				(width 0.1)
				(type default)
			)
			(layer "B.SilkS")
		)
		(fp_line
			(start -1.143 -0.5588)
			(end 1.143 -0.5588)
			(stroke
				(width 0.1)
				(type default)
			)
			(layer "B.SilkS")
		)
		(fp_rect
			(start 1.143 -0.5588)
			(end -1.143 0.5588)
			(stroke
				(width 0)
				(type default)
			)
			(fill no)
			(layer "B.CrtYd")
		)
		(fp_line
			(start 0.508 0.3048)
			(end -0.508 0.3048)
			(stroke
				(width 0.1)
				(type default)
			)
			(layer "B.Fab")
		)
		(fp_line
			(start 0.508 -0.3048)
			(end 0.508 0.3048)
			(stroke
				(width 0.1)
				(type default)
			)
			(layer "B.Fab")
		)
		(fp_line
			(start -0.508 0.3048)
			(end -0.508 -0.3048)
			(stroke
				(width 0.1)
				(type default)
			)
			(layer "B.Fab")
		)
		(fp_line
			(start -0.508 -0.3048)
			(end 0.508 -0.3048)
			(stroke
				(width 0.1)
				(type default)
			)
			(layer "B.Fab")
		)
		(pad "1" smd rect
			(at 0.5334 0)
			(size 0.7112 0.6096)
			(layers "B.Cu" "B.Mask" "B.Paste")
			(net "XP3R3V_FPGA")
		)
		(pad "2" smd rect
			(at -0.5334 0)
			(size 0.7112 0.6096)
			(layers "B.Cu" "B.Mask" "B.Paste")
			(net "SG")
		)
		(zone
			(layer "B.Cu")
			(hatch none 0.5)
			(connect_pads
				(clearance 0)
			)
			(min_thickness 0.25)
			(keepout
				(tracks allowed)
				(vias not_allowed)
				(pads allowed)
				(copperpour not_allowed)
				(footprints allowed)
			)
			(placement
				(enabled no)
				(sheetname "")
			)
			(fill
				(thermal_gap 0.5)
				(thermal_bridge_width 0.5)
				(island_removal_mode 0)
			)
			(polygon
				(pts
					(xy 115.090194 -44.2722) (xy 115.242594 -44.2722) (xy 115.242594 -44.8818) (xy 115.090194 -44.8818)
				)
			)
		)
	)
	(footprint ""
		(layer "B.Cu")
		(at 88.519 -85.598 180)
		(property "Reference" "R199"
			(at -0.254 5.42163 0)
			(unlocked yes)
			(layer "B.SilkS")
			(effects
				(font
					(size 0.7874 0.5842)
					(thickness 0.1524)
				)
				(justify mirror)
			)
		)
		(property "Value" "VAL*"
			(at -0.02032 2.13233 180)
			(unlocked yes)
			(layer "B.Fab")
			(hide yes)
			(effects
				(font
					(size 0.7874 0.5842)
					(thickness 0.1524)
				)
				(justify mirror)
			)
		)
		(property "Tolerance" "TOL*"
			(at -0.044704 3.05435 180)
			(unlocked yes)
			(layer "Cmts.User")
			(hide yes)
			(effects
				(font
					(size 0.7874 0.5842)
					(thickness 0.1524)
				)
				(justify mirror)
			)
		)
		(property "User Part Number" "PARTNUM*"
			(at -0.02032 4.024884 180)
			(unlocked yes)
			(layer "Cmts.User")
			(hide yes)
			(effects
				(font
					(size 0.7874 0.5842)
					(thickness 0.1524)
				)
				(justify mirror)
			)
		)
		(property "Device Type" "RESISTOR-G155-14701-01,4.7KOHMA"
			(at -0.008382 1.210564 180)
			(unlocked yes)
			(layer "B.Fab")
			(hide yes)
			(effects
				(font
					(size 0.7874 0.5842)
					(thickness 0.1524)
				)
				(justify mirror)
			)
		)
		(duplicate_pad_numbers_are_jumpers no)
		(fp_line
			(start 1.143 0.5588)
			(end -1.143 0.5588)
			(stroke
				(width 0.1)
				(type default)
			)
			(layer "B.SilkS")
		)
		(fp_line
			(start 1.143 -0.5588)
			(end 1.143 0.5588)
			(stroke
				(width 0.1)
				(type default)
			)
			(layer "B.SilkS")
		)
		(fp_line
			(start -1.143 0.5588)
			(end -1.143 -0.5588)
			(stroke
				(width 0.1)
				(type default)
			)
			(layer "B.SilkS")
		)
		(fp_line
			(start -1.143 -0.5588)
			(end 1.143 -0.5588)
			(stroke
				(width 0.1)
				(type default)
			)
			(layer "B.SilkS")
		)
		(fp_rect
			(start 1.143 -0.5588)
			(end -1.143 0.5588)
			(stroke
				(width 0)
				(type default)
			)
			(fill no)
			(layer "B.CrtYd")
		)
		(fp_line
			(start 0.508 0.3048)
			(end -0.508 0.3048)
			(stroke
				(width 0.1)
				(type default)
			)
			(layer "B.Fab")
		)
		(fp_line
			(start 0.508 -0.3048)
			(end 0.508 0.3048)
			(stroke
				(width 0.1)
				(type default)
			)
			(layer "B.Fab")
		)
		(fp_line
			(start -0.508 0.3048)
			(end -0.508 -0.3048)
			(stroke
				(width 0.1)
				(type default)
			)
			(layer "B.Fab")
		)
		(fp_line
			(start -0.508 -0.3048)
			(end 0.508 -0.3048)
			(stroke
				(width 0.1)
				(type default)
			)
			(layer "B.Fab")
		)
		(pad "1" smd rect
			(at 0.5334 0)
			(size 0.7112 0.6096)
			(layers "B.Cu" "B.Mask" "B.Paste")
			(net "UNNAMED_127_MT25QL128ABA1ESESOP")
		)
		(pad "2" smd rect
			(at -0.5334 0)
			(size 0.7112 0.6096)
			(layers "B.Cu" "B.Mask" "B.Paste")
			(net "XP3R3V_FPGA")
		)
		(zone
			(layer "B.Cu")
			(hatch none 0.5)
			(connect_pads
				(clearance 0)
			)
			(min_thickness 0.25)
			(keepout
				(tracks allowed)
				(vias not_allowed)
				(pads allowed)
				(copperpour not_allowed)
				(footprints allowed)
			)
			(placement
				(enabled no)
				(sheetname "")
			)
			(fill
				(thermal_gap 0.5)
				(thermal_bridge_width 0.5)
				(island_removal_mode 0)
			)
			(polygon
				(pts
					(xy 88.4428 -85.2932) (xy 88.5952 -85.2932) (xy 88.5952 -85.9028) (xy 88.4428 -85.9028)
				)
			)
		)
	)
)
